(kicad_pcb
	(version 20260206)
	(generator "pcbnew")
	(generator_version "10.0")
	(general
		(thickness 1.6)
		(legacy_teardrops no)
	)
	(paper "A4")
	(title_block
		(title "01162023_DA0F0TEBIF0_F0T_Expander_BD_F_brd_V02_OCP.brd")
		(comment 1 "Grand Teton / footprints 1453-1459 of 9728")
	)
	(layers
		(0 "F.Cu" signal "TOP")
		(4 "In1.Cu" signal "GND")
		(6 "In2.Cu" signal "VCC")
		(8 "In3.Cu" signal "VCC1")
		(10 "In4.Cu" signal "GND1")
		(12 "In5.Cu" signal "IN1")
		(14 "In6.Cu" signal "GND2")
		(16 "In7.Cu" signal "IN2")
		(18 "In8.Cu" signal "GND3")
		(20 "In9.Cu" signal "IN3")
		(22 "In10.Cu" signal "GND4")
		(24 "In11.Cu" signal "IN4")
		(26 "In12.Cu" signal "GND5")
		(28 "In13.Cu" signal "IN5")
		(30 "In14.Cu" signal "GND6")
		(32 "In15.Cu" signal "IN6")
		(34 "In16.Cu" signal "GND7")
		(2 "B.Cu" signal "BOTTOM")
		(9 "F.Adhes" user "F.Adhesive")
		(11 "B.Adhes" user "B.Adhesive")
		(13 "F.Paste" user "Package Geometry/Pastemask Top")
		(15 "B.Paste" user "Package Geometry/Pastemask Bottom")
		(5 "F.SilkS" user "Ref Des/Silkscreen Top")
		(7 "B.SilkS" user "Ref Des/Silkscreen Bottom")
		(1 "F.Mask" user "Board Geometry/Soldermask Top")
		(3 "B.Mask" user "Board Geometry/Soldermask Bottom")
		(17 "Dwgs.User" user "User.Drawings")
		(19 "Cmts.User" user "User.Comments")
		(21 "Eco1.User" user "User.Eco1")
		(23 "Eco2.User" user "User.Eco2")
		(25 "Edge.Cuts" user "Board Geometry/Outline")
		(27 "Margin" user)
		(31 "F.CrtYd" user "Package Geometry/Place Bound Top")
		(29 "B.CrtYd" user "Package Geometry/Place Bound Bottom")
		(35 "F.Fab" user "Ref Des/Assembly Top")
		(33 "B.Fab" user "Ref Des/Assembly Bottom")
	)
	(footprint ""
		(layer "F.Cu")
		(at 427.632114 -32.848042 90)
		(property "Reference" "PC977"
			(at 0 0 90)
			(layer "F.SilkS")
			(hide yes)
			(effects
				(font
					(size 1.27 1.27)
				)
			)
		)
		(property "Value" ""
			(at 0 0 90)
			(layer "F.Fab")
			(effects
				(font
					(size 1.27 1.27)
				)
			)
		)
		(duplicate_pad_numbers_are_jumpers no)
		(fp_line
			(start 0.7874 -0.4064)
			(end 0.7874 0.4064)
			(stroke
				(width 0.1524)
				(type default)
			)
			(layer "F.SilkS")
		)
		(fp_line
			(start -0.7874 -0.4064)
			(end 0.7874 -0.4064)
			(stroke
				(width 0.1524)
				(type default)
			)
			(layer "F.SilkS")
		)
		(fp_line
			(start 0.7874 0.4064)
			(end -0.7874 0.4064)
			(stroke
				(width 0.1524)
				(type default)
			)
			(layer "F.SilkS")
		)
		(fp_line
			(start -0.7874 0.4064)
			(end -0.7874 -0.4064)
			(stroke
				(width 0.1524)
				(type default)
			)
			(layer "F.SilkS")
		)
		(fp_line
			(start -0.12065 -0.305054)
			(end -0.12065 -0.2794)
			(stroke
				(width 0.1)
				(type default)
			)
			(layer "F.Fab")
		)
		(fp_line
			(start -0.67945 -0.305054)
			(end -0.12065 -0.305054)
			(stroke
				(width 0.1)
				(type default)
			)
			(layer "F.Fab")
		)
		(fp_line
			(start 0.67945 -0.3048)
			(end 0.67945 0.3048)
			(stroke
				(width 0.1)
				(type default)
			)
			(layer "F.Fab")
		)
		(fp_line
			(start 0.12065 -0.3048)
			(end 0.67945 -0.3048)
			(stroke
				(width 0.1)
				(type default)
			)
			(layer "F.Fab")
		)
		(fp_line
			(start 0.12065 -0.2794)
			(end 0.12065 -0.3048)
			(stroke
				(width 0.1)
				(type default)
			)
			(layer "F.Fab")
		)
		(fp_line
			(start -0.12065 -0.2794)
			(end 0.12065 -0.2794)
			(stroke
				(width 0.1)
				(type default)
			)
			(layer "F.Fab")
		)
		(fp_line
			(start 0.120396 0.2794)
			(end -0.12065 0.2794)
			(stroke
				(width 0.1)
				(type default)
			)
			(layer "F.Fab")
		)
		(fp_line
			(start -0.12065 0.2794)
			(end -0.12065 0.3048)
			(stroke
				(width 0.1)
				(type default)
			)
			(layer "F.Fab")
		)
		(fp_line
			(start 0.67945 0.3048)
			(end 0.120396 0.3048)
			(stroke
				(width 0.1)
				(type default)
			)
			(layer "F.Fab")
		)
		(fp_line
			(start 0.120396 0.3048)
			(end 0.120396 0.2794)
			(stroke
				(width 0.1)
				(type default)
			)
			(layer "F.Fab")
		)
		(fp_line
			(start -0.12065 0.3048)
			(end -0.67945 0.3048)
			(stroke
				(width 0.1)
				(type default)
			)
			(layer "F.Fab")
		)
		(fp_line
			(start -0.67945 0.3048)
			(end -0.67945 -0.305054)
			(stroke
				(width 0.1)
				(type default)
			)
			(layer "F.Fab")
		)
		(pad "1" smd circle
			(at -0.40005 0 90)
			(size 0 0)
			(layers "F.Cu" "F.Mask" "F.Paste")
			(net "P3V3_SSD15_CO_DV_DT")
		)
		(pad "2" smd circle
			(at 0.40005 0 90)
			(size 0 0)
			(layers "F.Cu" "F.Mask" "F.Paste")
			(net "GND")
		)
	)
	(footprint ""
		(layer "F.Cu")
		(at 188.614558 -66.32194 90)
		(property "Reference" "R5980"
			(at 0 0 90)
			(layer "F.SilkS")
			(hide yes)
			(effects
				(font
					(size 1.27 1.27)
				)
			)
		)
		(property "Value" ""
			(at 0 0 90)
			(layer "F.Fab")
			(effects
				(font
					(size 1.27 1.27)
				)
			)
		)
		(duplicate_pad_numbers_are_jumpers no)
		(fp_line
			(start 0.7874 -0.4064)
			(end 0.7874 0.4064)
			(stroke
				(width 0.1524)
				(type default)
			)
			(layer "F.SilkS")
		)
		(fp_line
			(start -0.7874 -0.4064)
			(end 0.7874 -0.4064)
			(stroke
				(width 0.1524)
				(type default)
			)
			(layer "F.SilkS")
		)
		(fp_line
			(start 0.7874 0.4064)
			(end -0.7874 0.4064)
			(stroke
				(width 0.1524)
				(type default)
			)
			(layer "F.SilkS")
		)
		(fp_line
			(start -0.7874 0.4064)
			(end -0.7874 -0.4064)
			(stroke
				(width 0.1524)
				(type default)
			)
			(layer "F.SilkS")
		)
		(fp_line
			(start -0.12065 -0.305054)
			(end -0.12065 -0.2794)
			(stroke
				(width 0.1)
				(type default)
			)
			(layer "F.Fab")
		)
		(fp_line
			(start -0.67945 -0.305054)
			(end -0.12065 -0.305054)
			(stroke
				(width 0.1)
				(type default)
			)
			(layer "F.Fab")
		)
		(fp_line
			(start 0.67945 -0.3048)
			(end 0.67945 0.3048)
			(stroke
				(width 0.1)
				(type default)
			)
			(layer "F.Fab")
		)
		(fp_line
			(start 0.12065 -0.3048)
			(end 0.67945 -0.3048)
			(stroke
				(width 0.1)
				(type default)
			)
			(layer "F.Fab")
		)
		(fp_line
			(start 0.12065 -0.2794)
			(end 0.12065 -0.3048)
			(stroke
				(width 0.1)
				(type default)
			)
			(layer "F.Fab")
		)
		(fp_line
			(start -0.12065 -0.2794)
			(end 0.12065 -0.2794)
			(stroke
				(width 0.1)
				(type default)
			)
			(layer "F.Fab")
		)
		(fp_line
			(start 0.120396 0.2794)
			(end -0.12065 0.2794)
			(stroke
				(width 0.1)
				(type default)
			)
			(layer "F.Fab")
		)
		(fp_line
			(start -0.12065 0.2794)
			(end -0.12065 0.3048)
			(stroke
				(width 0.1)
				(type default)
			)
			(layer "F.Fab")
		)
		(fp_line
			(start 0.67945 0.3048)
			(end 0.120396 0.3048)
			(stroke
				(width 0.1)
				(type default)
			)
			(layer "F.Fab")
		)
		(fp_line
			(start 0.120396 0.3048)
			(end 0.120396 0.2794)
			(stroke
				(width 0.1)
				(type default)
			)
			(layer "F.Fab")
		)
		(fp_line
			(start -0.12065 0.3048)
			(end -0.67945 0.3048)
			(stroke
				(width 0.1)
				(type default)
			)
			(layer "F.Fab")
		)
		(fp_line
			(start -0.67945 0.3048)
			(end -0.67945 -0.305054)
			(stroke
				(width 0.1)
				(type default)
			)
			(layer "F.Fab")
		)
		(pad "1" smd circle
			(at -0.40005 0 90)
			(size 0 0)
			(layers "F.Cu" "F.Mask" "F.Paste")
			(net "SSD6_PWR_EN_R")
		)
		(pad "2" smd circle
			(at 0.40005 0 90)
			(size 0 0)
			(layers "F.Cu" "F.Mask" "F.Paste")
			(net "P12V_SSD6_CO_EN")
		)
	)
	(footprint ""
		(layer "F.Cu")
		(at 198.230236 -107.552998 -90)
		(property "Reference" "C890"
			(at 0 0 270)
			(layer "F.SilkS")
			(hide yes)
			(effects
				(font
					(size 1.27 1.27)
				)
			)
		)
		(property "Value" ""
			(at 0 0 270)
			(layer "F.Fab")
			(effects
				(font
					(size 1.27 1.27)
				)
			)
		)
		(duplicate_pad_numbers_are_jumpers no)
		(fp_line
			(start -1.524 0.762)
			(end -1.524 -0.762)
			(stroke
				(width 0.1524)
				(type default)
			)
			(layer "F.SilkS")
		)
		(fp_line
			(start 1.524 0.762)
			(end -1.524 0.762)
			(stroke
				(width 0.1524)
				(type default)
			)
			(layer "F.SilkS")
		)
		(fp_line
			(start -1.524 -0.762)
			(end 1.524 -0.762)
			(stroke
				(width 0.1524)
				(type default)
			)
			(layer "F.SilkS")
		)
		(fp_line
			(start 1.524 -0.762)
			(end 1.524 0.762)
			(stroke
				(width 0.1524)
				(type default)
			)
			(layer "F.SilkS")
		)
		(fp_line
			(start -1.1049 0.724916)
			(end 1.1049 0.724916)
			(stroke
				(width 0.1)
				(type default)
			)
			(layer "F.Fab")
		)
		(fp_line
			(start 1.1049 0.724916)
			(end 1.1049 -0.724916)
			(stroke
				(width 0.1)
				(type default)
			)
			(layer "F.Fab")
		)
		(fp_line
			(start -1.1049 -0.724916)
			(end -1.1049 0.724916)
			(stroke
				(width 0.1)
				(type default)
			)
			(layer "F.Fab")
		)
		(fp_line
			(start 1.1049 -0.724916)
			(end -1.1049 -0.724916)
			(stroke
				(width 0.1)
				(type default)
			)
			(layer "F.Fab")
		)
		(pad "1" smd rect
			(at -0.889 0 90)
			(size 1.016 1.27)
			(layers "F.Cu" "F.Mask" "F.Paste")
			(net "P12V_NIC3")
		)
		(pad "2" smd rect
			(at 0.889 0 90)
			(size 1.016 1.27)
			(layers "F.Cu" "F.Mask" "F.Paste")
			(net "GND")
		)
	)
	(footprint ""
		(layer "F.Cu")
		(at 373.362474 -22.955504 -90)
		(property "Reference" "C2731"
			(at 0 0 270)
			(layer "F.SilkS")
			(hide yes)
			(effects
				(font
					(size 1.27 1.27)
				)
			)
		)
		(property "Value" ""
			(at 0 0 270)
			(layer "F.Fab")
			(effects
				(font
					(size 1.27 1.27)
				)
			)
		)
		(duplicate_pad_numbers_are_jumpers no)
		(fp_line
			(start -0.7874 0.4064)
			(end -0.7874 -0.4064)
			(stroke
				(width 0.1524)
				(type default)
			)
			(layer "F.SilkS")
		)
		(fp_line
			(start 0.7874 0.4064)
			(end -0.7874 0.4064)
			(stroke
				(width 0.1524)
				(type default)
			)
			(layer "F.SilkS")
		)
		(fp_line
			(start -0.7874 -0.4064)
			(end 0.7874 -0.4064)
			(stroke
				(width 0.1524)
				(type default)
			)
			(layer "F.SilkS")
		)
		(fp_line
			(start 0.7874 -0.4064)
			(end 0.7874 0.4064)
			(stroke
				(width 0.1524)
				(type default)
			)
			(layer "F.SilkS")
		)
		(fp_line
			(start -0.67945 0.3048)
			(end -0.67945 -0.305054)
			(stroke
				(width 0.1)
				(type default)
			)
			(layer "F.Fab")
		)
		(fp_line
			(start -0.12065 0.3048)
			(end -0.67945 0.3048)
			(stroke
				(width 0.1)
				(type default)
			)
			(layer "F.Fab")
		)
		(fp_line
			(start 0.120396 0.3048)
			(end 0.120396 0.2794)
			(stroke
				(width 0.1)
				(type default)
			)
			(layer "F.Fab")
		)
		(fp_line
			(start 0.67945 0.3048)
			(end 0.120396 0.3048)
			(stroke
				(width 0.1)
				(type default)
			)
			(layer "F.Fab")
		)
		(fp_line
			(start -0.12065 0.2794)
			(end -0.12065 0.3048)
			(stroke
				(width 0.1)
				(type default)
			)
			(layer "F.Fab")
		)
		(fp_line
			(start 0.120396 0.2794)
			(end -0.12065 0.2794)
			(stroke
				(width 0.1)
				(type default)
			)
			(layer "F.Fab")
		)
		(fp_line
			(start -0.12065 -0.2794)
			(end 0.12065 -0.2794)
			(stroke
				(width 0.1)
				(type default)
			)
			(layer "F.Fab")
		)
		(fp_line
			(start 0.12065 -0.2794)
			(end 0.12065 -0.3048)
			(stroke
				(width 0.1)
				(type default)
			)
			(layer "F.Fab")
		)
		(fp_line
			(start 0.12065 -0.3048)
			(end 0.67945 -0.3048)
			(stroke
				(width 0.1)
				(type default)
			)
			(layer "F.Fab")
		)
		(fp_line
			(start 0.67945 -0.3048)
			(end 0.67945 0.3048)
			(stroke
				(width 0.1)
				(type default)
			)
			(layer "F.Fab")
		)
		(fp_line
			(start -0.67945 -0.305054)
			(end -0.12065 -0.305054)
			(stroke
				(width 0.1)
				(type default)
			)
			(layer "F.Fab")
		)
		(fp_line
			(start -0.12065 -0.305054)
			(end -0.12065 -0.2794)
			(stroke
				(width 0.1)
				(type default)
			)
			(layer "F.Fab")
		)
		(pad "1" smd circle
			(at -0.40005 0 270)
			(size 0 0)
			(layers "F.Cu" "F.Mask" "F.Paste")
			(net "GND")
		)
		(pad "2" smd circle
			(at 0.40005 0 270)
			(size 0 0)
			(layers "F.Cu" "F.Mask" "F.Paste")
			(net "P3V3_AUX")
		)
	)
	(footprint ""
		(layer "F.Cu")
		(at 140.074142 -183.009286 180)
		(property "Reference" "R1108"
			(at 0 0 180)
			(layer "F.SilkS")
			(hide yes)
			(effects
				(font
					(size 1.27 1.27)
				)
			)
		)
		(property "Value" ""
			(at 0 0 180)
			(layer "F.Fab")
			(effects
				(font
					(size 1.27 1.27)
				)
			)
		)
		(duplicate_pad_numbers_are_jumpers no)
		(fp_line
			(start 0.7874 0.4064)
			(end -0.7874 0.4064)
			(stroke
				(width 0.1524)
				(type default)
			)
			(layer "F.SilkS")
		)
		(fp_line
			(start 0.67945 0.3048)
			(end 0.120396 0.3048)
			(stroke
				(width 0.1)
				(type default)
			)
			(layer "F.Fab")
		)
		(fp_line
			(start 0.67945 -0.3048)
			(end 0.67945 0.3048)
			(stroke
				(width 0.1)
				(type default)
			)
			(layer "F.Fab")
		)
		(fp_line
			(start 0.12065 -0.2794)
			(end 0.12065 -0.3048)
			(stroke
				(width 0.1)
				(type default)
			)
			(layer "F.Fab")
		)
		(fp_line
			(start 0.12065 -0.3048)
			(end 0.67945 -0.3048)
			(stroke
				(width 0.1)
				(type default)
			)
			(layer "F.Fab")
		)
		(fp_line
			(start 0.120396 0.3048)
			(end 0.120396 0.2794)
			(stroke
				(width 0.1)
				(type default)
			)
			(layer "F.Fab")
		)
		(fp_line
			(start 0.120396 0.2794)
			(end -0.12065 0.2794)
			(stroke
				(width 0.1)
				(type default)
			)
			(layer "F.Fab")
		)
		(fp_line
			(start -0.12065 0.3048)
			(end -0.67945 0.3048)
			(stroke
				(width 0.1)
				(type default)
			)
			(layer "F.Fab")
		)
		(fp_line
			(start -0.12065 0.2794)
			(end -0.12065 0.3048)
			(stroke
				(width 0.1)
				(type default)
			)
			(layer "F.Fab")
		)
		(fp_line
			(start -0.12065 -0.2794)
			(end 0.12065 -0.2794)
			(stroke
				(width 0.1)
				(type default)
			)
			(layer "F.Fab")
		)
		(fp_line
			(start -0.12065 -0.305054)
			(end -0.12065 -0.2794)
			(stroke
				(width 0.1)
				(type default)
			)
			(layer "F.Fab")
		)
		(fp_line
			(start -0.67945 0.3048)
			(end -0.67945 -0.305054)
			(stroke
				(width 0.1)
				(type default)
			)
			(layer "F.Fab")
		)
		(fp_line
			(start -0.67945 -0.305054)
			(end -0.12065 -0.305054)
			(stroke
				(width 0.1)
				(type default)
			)
			(layer "F.Fab")
		)
		(pad "1" smd circle
			(at -0.40005 0 180)
			(size 0 0)
			(layers "F.Cu" "F.Mask" "F.Paste")
			(net "CLK_100M_DB2000QL_NIC6_R_DN")
		)
		(pad "2" smd circle
			(at 0.40005 0 180)
			(size 0 0)
			(layers "F.Cu" "F.Mask" "F.Paste")
			(net "CLK_100M_DB2000QL_NIC6_DN")
		)
	)
	(footprint ""
		(layer "F.Cu")
		(at 381.254 -199.39)
		(property "Reference" "R4671"
			(at 0 0 0)
			(layer "F.SilkS")
			(hide yes)
			(effects
				(font
					(size 1.27 1.27)
				)
			)
		)
		(property "Value" ""
			(at 0 0 0)
			(layer "F.Fab")
			(effects
				(font
					(size 1.27 1.27)
				)
			)
		)
		(duplicate_pad_numbers_are_jumpers no)
		(fp_line
			(start -0.7874 -0.4064)
			(end 0.7874 -0.4064)
			(stroke
				(width 0.1524)
				(type default)
			)
			(layer "F.SilkS")
		)
		(fp_line
			(start -0.7874 0.4064)
			(end -0.7874 -0.4064)
			(stroke
				(width 0.1524)
				(type default)
			)
			(layer "F.SilkS")
		)
		(fp_line
			(start 0.7874 -0.4064)
			(end 0.7874 0.4064)
			(stroke
				(width 0.1524)
				(type default)
			)
			(layer "F.SilkS")
		)
		(fp_line
			(start 0.7874 0.4064)
			(end -0.7874 0.4064)
			(stroke
				(width 0.1524)
				(type default)
			)
			(layer "F.SilkS")
		)
		(fp_line
			(start -0.67945 -0.305054)
			(end -0.12065 -0.305054)
			(stroke
				(width 0.1)
				(type default)
			)
			(layer "F.Fab")
		)
		(fp_line
			(start -0.67945 0.3048)
			(end -0.67945 -0.305054)
			(stroke
				(width 0.1)
				(type default)
			)
			(layer "F.Fab")
		)
		(fp_line
			(start -0.12065 -0.305054)
			(end -0.12065 -0.2794)
			(stroke
				(width 0.1)
				(type default)
			)
			(layer "F.Fab")
		)
		(fp_line
			(start -0.12065 -0.2794)
			(end 0.12065 -0.2794)
			(stroke
				(width 0.1)
				(type default)
			)
			(layer "F.Fab")
		)
		(fp_line
			(start -0.12065 0.2794)
			(end -0.12065 0.3048)
			(stroke
				(width 0.1)
				(type default)
			)
			(layer "F.Fab")
		)
		(fp_line
			(start -0.12065 0.3048)
			(end -0.67945 0.3048)
			(stroke
				(width 0.1)
				(type default)
			)
			(layer "F.Fab")
		)
		(fp_line
			(start 0.120396 0.2794)
			(end -0.12065 0.2794)
			(stroke
				(width 0.1)
				(type default)
			)
			(layer "F.Fab")
		)
		(fp_line
			(start 0.120396 0.3048)
			(end 0.120396 0.2794)
			(stroke
				(width 0.1)
				(type default)
			)
			(layer "F.Fab")
		)
		(fp_line
			(start 0.12065 -0.3048)
			(end 0.67945 -0.3048)
			(stroke
				(width 0.1)
				(type default)
			)
			(layer "F.Fab")
		)
		(fp_line
			(start 0.12065 -0.2794)
			(end 0.12065 -0.3048)
			(stroke
				(width 0.1)
				(type default)
			)
			(layer "F.Fab")
		)
		(fp_line
			(start 0.67945 -0.3048)
			(end 0.67945 0.3048)
			(stroke
				(width 0.1)
				(type default)
			)
			(layer "F.Fab")
		)
		(fp_line
			(start 0.67945 0.3048)
			(end 0.120396 0.3048)
			(stroke
				(width 0.1)
				(type default)
			)
			(layer "F.Fab")
		)
		(pad "1" smd circle
			(at -0.40005 0)
			(size 0 0)
			(layers "F.Cu" "F.Mask" "F.Paste")
			(net "P3V3_AUX")
		)
		(pad "2" smd circle
			(at 0.40005 0)
			(size 0 0)
			(layers "F.Cu" "F.Mask" "F.Paste")
			(net "RST_PEX_NIC2_PERST_R_N")
		)
	)
	(footprint ""
		(layer "F.Cu")
		(at 198.40194 -404.113238 -90)
		(property "Reference" "R5714"
			(at 0 0 270)
			(layer "F.SilkS")
			(hide yes)
			(effects
				(font
					(size 1.27 1.27)
				)
			)
		)
		(property "Value" ""
			(at 0 0 270)
			(layer "F.Fab")
			(effects
				(font
					(size 1.27 1.27)
				)
			)
		)
		(duplicate_pad_numbers_are_jumpers no)
		(fp_line
			(start -0.7874 0.4064)
			(end -0.7874 -0.4064)
			(stroke
				(width 0.1524)
				(type default)
			)
			(layer "F.SilkS")
		)
		(fp_line
			(start 0.7874 0.4064)
			(end -0.7874 0.4064)
			(stroke
				(width 0.1524)
				(type default)
			)
			(layer "F.SilkS")
		)
		(fp_line
			(start -0.7874 -0.4064)
			(end 0.7874 -0.4064)
			(stroke
				(width 0.1524)
				(type default)
			)
			(layer "F.SilkS")
		)
		(fp_line
			(start 0.7874 -0.4064)
			(end 0.7874 0.4064)
			(stroke
				(width 0.1524)
				(type default)
			)
			(layer "F.SilkS")
		)
		(fp_line
			(start -0.67945 0.3048)
			(end -0.67945 -0.305054)
			(stroke
				(width 0.1)
				(type default)
			)
			(layer "F.Fab")
		)
		(fp_line
			(start -0.12065 0.3048)
			(end -0.67945 0.3048)
			(stroke
				(width 0.1)
				(type default)
			)
			(layer "F.Fab")
		)
		(fp_line
			(start 0.120396 0.3048)
			(end 0.120396 0.2794)
			(stroke
				(width 0.1)
				(type default)
			)
			(layer "F.Fab")
		)
		(fp_line
			(start 0.67945 0.3048)
			(end 0.120396 0.3048)
			(stroke
				(width 0.1)
				(type default)
			)
			(layer "F.Fab")
		)
		(fp_line
			(start -0.12065 0.2794)
			(end -0.12065 0.3048)
			(stroke
				(width 0.1)
				(type default)
			)
			(layer "F.Fab")
		)
		(fp_line
			(start 0.120396 0.2794)
			(end -0.12065 0.2794)
			(stroke
				(width 0.1)
				(type default)
			)
			(layer "F.Fab")
		)
		(fp_line
			(start -0.12065 -0.2794)
			(end 0.12065 -0.2794)
			(stroke
				(width 0.1)
				(type default)
			)
			(layer "F.Fab")
		)
		(fp_line
			(start 0.12065 -0.2794)
			(end 0.12065 -0.3048)
			(stroke
				(width 0.1)
				(type default)
			)
			(layer "F.Fab")
		)
		(fp_line
			(start 0.12065 -0.3048)
			(end 0.67945 -0.3048)
			(stroke
				(width 0.1)
				(type default)
			)
			(layer "F.Fab")
		)
		(fp_line
			(start 0.67945 -0.3048)
			(end 0.67945 0.3048)
			(stroke
				(width 0.1)
				(type default)
			)
			(layer "F.Fab")
		)
		(fp_line
			(start -0.67945 -0.305054)
			(end -0.12065 -0.305054)
			(stroke
				(width 0.1)
				(type default)
			)
			(layer "F.Fab")
		)
		(fp_line
			(start -0.12065 -0.305054)
			(end -0.12065 -0.2794)
			(stroke
				(width 0.1)
				(type default)
			)
			(layer "F.Fab")
		)
		(pad "1" smd circle
			(at -0.40005 0 270)
			(size 0 0)
			(layers "F.Cu" "F.Mask" "F.Paste")
			(net "MB_HSC_ISO_D2_EN")
		)
		(pad "2" smd circle
			(at 0.40005 0 270)
			(size 0 0)
			(layers "F.Cu" "F.Mask" "F.Paste")
			(net "HSC_P12V_EN")
		)
	)
)
